#ISCELL
  pure_quanta quanta_title_block_c *
  *
#ISCELL
  pure_quanta_power cad_note *
  *
#CELL
  pure_quanta genoa_sp5 *
  page41_i159
#ISCELL
  mstr_standard offpage *
  page41_i160
#ISCELL
  mstr_standard offpage *
  page41_i161
#ISCELL
  mstr_standard tap *
  page41_i162
#ISCELL
  mstr_standard tap *
  page41_i163
#ISCELL
  mstr_standard tap *
  page41_i164
#ISCELL
  mstr_standard tap *
  page41_i165
#ISCELL
  mstr_standard tap *
  page41_i166
#ISCELL
  mstr_standard tap *
  page41_i167
#ISCELL
  mstr_standard tap *
  page41_i168
#ISCELL
  mstr_standard tap *
  page41_i169
#ISCELL
  mstr_standard tap *
  page41_i170
#ISCELL
  mstr_standard tap *
  page41_i171
#ISCELL
  mstr_standard tap *
  page41_i172
#ISCELL
  mstr_standard tap *
  page41_i173
#ISCELL
  mstr_standard tap *
  page41_i174
#ISCELL
  mstr_standard tap *
  page41_i175
#ISCELL
  mstr_standard tap *
  page41_i176
#ISCELL
  mstr_standard tap *
  page41_i177
#ISCELL
  mstr_standard tap *
  page41_i178
#ISCELL
  mstr_standard tap *
  page41_i179
#ISCELL
  mstr_standard tap *
  page41_i180
#ISCELL
  mstr_standard tap *
  page41_i181
#ISCELL
  mstr_standard tap *
  page41_i182
#ISCELL
  mstr_standard tap *
  page41_i183
#ISCELL
  mstr_standard tap *
  page41_i184
#ISCELL
  mstr_standard tap *
  page41_i185
#ISCELL
  mstr_standard tap *
  page41_i186
#ISCELL
  mstr_standard tap *
  page41_i187
#ISCELL
  mstr_standard tap *
  page41_i188
#ISCELL
  mstr_standard tap *
  page41_i189
#ISCELL
  mstr_standard tap *
  page41_i190
#ISCELL
  mstr_standard tap *
  page41_i191
#ISCELL
  mstr_standard tap *
  page41_i192
#ISCELL
  mstr_standard tap *
  page41_i193
#ISCELL
  mstr_standard tap *
  page41_i194
#ISCELL
  mstr_standard tap *
  page41_i195
#ISCELL
  mstr_standard offpage *
  page41_i196
#ISCELL
  mstr_standard tap *
  page41_i197
#ISCELL
  mstr_standard tap *
  page41_i198
#ISCELL
  mstr_standard tap *
  page41_i199
#ISCELL
  mstr_standard tap *
  page41_i200
#ISCELL
  mstr_standard tap *
  page41_i201
#ISCELL
  mstr_standard tap *
  page41_i202
#ISCELL
  mstr_standard tap *
  page41_i203
#ISCELL
  mstr_standard tap *
  page41_i204
#ISCELL
  mstr_standard tap *
  page41_i205
#ISCELL
  mstr_standard tap *
  page41_i206
#ISCELL
  mstr_standard tap *
  page41_i207
#ISCELL
  mstr_standard tap *
  page41_i208
#ISCELL
  mstr_standard tap *
  page41_i209
#ISCELL
  mstr_standard tap *
  page41_i210
#ISCELL
  mstr_standard tap *
  page41_i211
#ISCELL
  mstr_standard tap *
  page41_i212
#ISCELL
  mstr_standard tap *
  page41_i213
#ISCELL
  mstr_standard tap *
  page41_i214
#ISCELL
  mstr_standard tap *
  page41_i215
#ISCELL
  mstr_standard tap *
  page41_i216
#ISCELL
  mstr_standard tap *
  page41_i217
#ISCELL
  mstr_standard tap *
  page41_i218
#ISCELL
  mstr_standard tap *
  page41_i219
#ISCELL
  mstr_standard tap *
  page41_i220
#ISCELL
  mstr_standard tap *
  page41_i221
#ISCELL
  mstr_standard tap *
  page41_i222
#ISCELL
  mstr_standard tap *
  page41_i223
#ISCELL
  mstr_standard tap *
  page41_i224
#ISCELL
  mstr_standard tap *
  page41_i225
#ISCELL
  mstr_standard tap *
  page41_i226
#ISCELL
  mstr_standard tap *
  page41_i227
#ISCELL
  mstr_standard tap *
  page41_i228
#ISCELL
  mstr_standard tap *
  page41_i229
#ISCELL
  mstr_standard tap *
  page41_i230
#ISCELL
  mstr_standard tap *
  page41_i231
#ISCELL
  mstr_standard tap *
  page41_i232
#ISCELL
  mstr_standard tap *
  page41_i233
#ISCELL
  mstr_standard offpage *
  page41_i234
#ISCELL
  mstr_standard tap *
  page41_i235
#ISCELL
  mstr_standard tap *
  page41_i236
#ISCELL
  mstr_standard tap *
  page41_i237
#ISCELL
  mstr_standard tap *
  page41_i238
#ISCELL
  mstr_standard tap *
  page41_i239
#ISCELL
  mstr_standard tap *
  page41_i240
#ISCELL
  mstr_standard tap *
  page41_i241
#ISCELL
  mstr_standard tap *
  page41_i242
#ISCELL
  mstr_standard tap *
  page41_i243
#ISCELL
  mstr_standard tap *
  page41_i244
#ISCELL
  mstr_standard tap *
  page41_i245
#ISCELL
  mstr_standard tap *
  page41_i246
#ISCELL
  mstr_standard tap *
  page41_i247
#ISCELL
  mstr_standard tap *
  page41_i248
#ISCELL
  mstr_standard tap *
  page41_i249
#ISCELL
  mstr_standard tap *
  page41_i250
#ISCELL
  mstr_standard tap *
  page41_i251
#ISCELL
  mstr_standard tap *
  page41_i252
#ISCELL
  mstr_standard tap *
  page41_i253
#ISCELL
  mstr_standard tap *
  page41_i254
#ISCELL
  mstr_standard tap *
  page41_i255
#ISCELL
  mstr_standard tap *
  page41_i256
#ISCELL
  mstr_standard tap *
  page41_i257
#ISCELL
  mstr_standard tap *
  page41_i258
#ISCELL
  mstr_standard tap *
  page41_i259
#ISCELL
  mstr_standard tap *
  page41_i260
#ISCELL
  mstr_standard tap *
  page41_i261
#ISCELL
  mstr_standard tap *
  page41_i262
#ISCELL
  mstr_standard tap *
  page41_i263
#ISCELL
  mstr_standard tap *
  page41_i264
#ISCELL
  mstr_standard tap *
  page41_i265
#ISCELL
  mstr_standard tap *
  page41_i266
#ISCELL
  mstr_standard tap *
  page41_i267
#ISCELL
  mstr_standard tap *
  page41_i268
#ISCELL
  mstr_standard tap *
  page41_i269
#ISCELL
  mstr_standard tap *
  page41_i270
#ISCELL
  mstr_standard tap *
  page41_i271
#ISCELL
  mstr_standard tap *
  page41_i272
#ISCELL
  mstr_standard tap *
  page41_i273
#ISCELL
  mstr_standard tap *
  page41_i274
#ISCELL
  mstr_standard tap *
  page41_i275
#ISCELL
  mstr_standard tap *
  page41_i276
#ISCELL
  mstr_standard tap *
  page41_i277
#ISCELL
  mstr_standard tap *
  page41_i278
#ISCELL
  mstr_standard tap *
  page41_i279
#ISCELL
  mstr_standard tap *
  page41_i280
#ISCELL
  standard offpage *
  page41_i281
#ISCELL
  standard offpage *
  page41_i282
#ISCELL
  standard offpage *
  page41_i283
#ISCELL
  standard offpage *
  page41_i284
#ISCELL
  mstr_standard tap *
  page41_i285
#ISCELL
  mstr_standard tap *
  page41_i286
#ISCELL
  mstr_standard tap *
  page41_i287
#ISCELL
  mstr_standard tap *
  page41_i288
#ISCELL
  mstr_standard tap *
  page41_i289
#ISCELL
  mstr_standard tap *
  page41_i290
#ISCELL
  mstr_standard tap *
  page41_i291
#ISCELL
  mstr_standard tap *
  page41_i292
#ISCELL
  mstr_standard tap *
  page41_i293
#ISCELL
  mstr_standard tap *
  page41_i294
#ISCELL
  mstr_standard tap *
  page41_i295
#ISCELL
  mstr_standard tap *
  page41_i296
#ISCELL
  mstr_standard tap *
  page41_i297
#ISCELL
  mstr_standard tap *
  page41_i298
#ISCELL
  mstr_standard tap *
  page41_i299
#ISCELL
  mstr_standard tap *
  page41_i300
#ISCELL
  mstr_standard tap *
  page41_i301
#ISCELL
  standard offpage *
  page41_i302
#ISCELL
  standard offpage *
  page41_i303
#ISCELL
  standard offpage *
  page41_i304
#ISCELL
  standard offpage *
  page41_i305
#ISCELL
  standard offpage *
  page41_i306
#ISCELL
  standard offpage *
  page41_i307
#ISCELL
  standard offpage *
  page41_i308
#ISCELL
  mstr_standard offpage *
  page41_i309
#ISCELL
  standard offpage *
  page41_i310
#ISCELL
  standard offpage *
  page41_i311
#ISCELL
  standard offpage *
  page41_i312
#ISCELL
  standard offpage *
  page41_i313
#CELL
  pure_quanta q_res *
  page41_i314
#ISCELL
  mstr_standard offpage *
  page41_i315
#ISCELL
  standard offpage *
  page41_i316
